# S9S_MB_2U (Grand Teton) — schematic netlist excerpt (pin names and nets, part order shuffled) for the footprints in the layout excerpt that follows; sources: Cadence DE-HDL packaged netlist, KiCad conversion of 03242023_DA0F0TMBIJ0_F0T_Motherboard_J_brd_V01_OCP.brd

R4543  Q_RES  4.7K 5% CHIP  pkg 0402LF  page 145 : A = P3V3_AUX ; B = HGX_DETECT_N
ME2  ME_DUMMY_SYMBOL  PICKUP_SMDC20 EMPTY  pkg PICKUP_SMDC20  page 312
R2400  Q_RES  0 5% CHIP  pkg 0402LF  page 278 : A = SVID_DIO1_CPU0_R ; B = SVID_DIO_PVCCD_HV_CPU0_R

(kicad_pcb
	(version 20260206)
	(generator "pcbnew")
	(generator_version "10.0")
	(general
		(thickness 1.6)
		(legacy_teardrops no)
	)
	(paper "A4")
	(title_block
		(title "03242023_DA0F0TMBIJ0_F0T_Motherboard_J_brd_V01_OCP.brd")
		(comment 1 "Grand Teton / footprints 3879-3881 of 6105")
	)
	(layers
		(0 "F.Cu" signal "TOP")
		(4 "In1.Cu" signal "GND")
		(6 "In2.Cu" signal "IN1")
		(8 "In3.Cu" signal "GND1")
		(10 "In4.Cu" signal "IN2")
		(12 "In5.Cu" signal "GND2")
		(14 "In6.Cu" signal "IN3")
		(16 "In7.Cu" signal "GND3")
		(18 "In8.Cu" signal "VCC")
		(20 "In9.Cu" signal "VCC1")
		(22 "In10.Cu" signal "GND4")
		(24 "In11.Cu" signal "IN4")
		(26 "In12.Cu" signal "GND5")
		(28 "In13.Cu" signal "IN5")
		(30 "In14.Cu" signal "GND6")
		(32 "In15.Cu" signal "IN6")
		(34 "In16.Cu" signal "GND7")
		(2 "B.Cu" signal "BOTTOM")
		(9 "F.Adhes" user "F.Adhesive")
		(11 "B.Adhes" user "B.Adhesive")
		(13 "F.Paste" user "Package Geometry/Pastemask Top")
		(15 "B.Paste" user "Package Geometry/Pastemask Bottom")
		(5 "F.SilkS" user "Ref Des/Silkscreen Top")
		(7 "B.SilkS" user "Ref Des/Silkscreen Bottom")
		(1 "F.Mask" user "Board Geometry/Soldermask Top")
		(3 "B.Mask" user "Board Geometry/Soldermask Bottom")
		(17 "Dwgs.User" user "User.Drawings")
		(19 "Cmts.User" user "User.Comments")
		(21 "Eco1.User" user "User.Eco1")
		(23 "Eco2.User" user "User.Eco2")
		(25 "Edge.Cuts" user "Board Geometry/Outline")
		(27 "Margin" user)
		(31 "F.CrtYd" user "Package Geometry/Place Bound Top")
		(29 "B.CrtYd" user "Package Geometry/Place Bound Bottom")
		(35 "F.Fab" user "Ref Des/Assembly Top")
		(33 "B.Fab" user "Ref Des/Assembly Bottom")
	)
	(footprint ""
		(layer "F.Cu")
		(at 98.13036 -412.171388 180)
		(property "Reference" "R4543"
			(at 0 0 180)
			(layer "F.SilkS")
			(hide yes)
			(effects
				(font
					(size 1.27 1.27)
				)
			)
		)
		(property "Value" ""
			(at 0 0 180)
			(layer "F.Fab")
			(effects
				(font
					(size 1.27 1.27)
				)
			)
		)
		(duplicate_pad_numbers_are_jumpers no)
		(fp_line
			(start 0.7874 0.4064)
			(end -0.7874 0.4064)
			(stroke
				(width 0.1524)
				(type default)
			)
			(layer "F.SilkS")
		)
		(fp_line
			(start 0.7874 -0.4064)
			(end 0.7874 0.4064)
			(stroke
				(width 0.1524)
				(type default)
			)
			(layer "F.SilkS")
		)
		(fp_line
			(start -0.7874 0.4064)
			(end -0.7874 -0.4064)
			(stroke
				(width 0.1524)
				(type default)
			)
			(layer "F.SilkS")
		)
		(fp_line
			(start -0.7874 -0.4064)
			(end 0.7874 -0.4064)
			(stroke
				(width 0.1524)
				(type default)
			)
			(layer "F.SilkS")
		)
		(fp_line
			(start 0.67945 0.3048)
			(end 0.120396 0.3048)
			(stroke
				(width 0.1)
				(type default)
			)
			(layer "F.Fab")
		)
		(fp_line
			(start 0.67945 -0.3048)
			(end 0.67945 0.3048)
			(stroke
				(width 0.1)
				(type default)
			)
			(layer "F.Fab")
		)
		(fp_line
			(start 0.12065 -0.2794)
			(end 0.12065 -0.3048)
			(stroke
				(width 0.1)
				(type default)
			)
			(layer "F.Fab")
		)
		(fp_line
			(start 0.12065 -0.3048)
			(end 0.67945 -0.3048)
			(stroke
				(width 0.1)
				(type default)
			)
			(layer "F.Fab")
		)
		(fp_line
			(start 0.120396 0.3048)
			(end 0.120396 0.2794)
			(stroke
				(width 0.1)
				(type default)
			)
			(layer "F.Fab")
		)
		(fp_line
			(start 0.120396 0.2794)
			(end -0.12065 0.2794)
			(stroke
				(width 0.1)
				(type default)
			)
			(layer "F.Fab")
		)
		(fp_line
			(start -0.12065 0.3048)
			(end -0.67945 0.3048)
			(stroke
				(width 0.1)
				(type default)
			)
			(layer "F.Fab")
		)
		(fp_line
			(start -0.12065 0.2794)
			(end -0.12065 0.3048)
			(stroke
				(width 0.1)
				(type default)
			)
			(layer "F.Fab")
		)
		(fp_line
			(start -0.12065 -0.2794)
			(end 0.12065 -0.2794)
			(stroke
				(width 0.1)
				(type default)
			)
			(layer "F.Fab")
		)
		(fp_line
			(start -0.12065 -0.305054)
			(end -0.12065 -0.2794)
			(stroke
				(width 0.1)
				(type default)
			)
			(layer "F.Fab")
		)
		(fp_line
			(start -0.67945 0.3048)
			(end -0.67945 -0.305054)
			(stroke
				(width 0.1)
				(type default)
			)
			(layer "F.Fab")
		)
		(fp_line
			(start -0.67945 -0.305054)
			(end -0.12065 -0.305054)
			(stroke
				(width 0.1)
				(type default)
			)
			(layer "F.Fab")
		)
		(pad "1" smd circle
			(at -0.40005 0 180)
			(size 0 0)
			(layers "F.Cu" "F.Mask" "F.Paste")
			(net "P3V3_AUX")
		)
		(pad "2" smd circle
			(at 0.40005 0 180)
			(size 0 0)
			(layers "F.Cu" "F.Mask" "F.Paste")
			(net "HGX_DETECT_N")
		)
	)
	(footprint ""
		(layer "F.Cu")
		(at 437.242966 -124.680726 180)
		(property "Reference" "R2400"
			(at 0 0 180)
			(layer "F.SilkS")
			(hide yes)
			(effects
				(font
					(size 1.27 1.27)
				)
			)
		)
		(property "Value" ""
			(at 0 0 180)
			(layer "F.Fab")
			(effects
				(font
					(size 1.27 1.27)
				)
			)
		)
		(duplicate_pad_numbers_are_jumpers no)
		(fp_line
			(start 0.7874 0.4064)
			(end -0.7874 0.4064)
			(stroke
				(width 0.1524)
				(type default)
			)
			(layer "F.SilkS")
		)
		(fp_line
			(start 0.7874 -0.4064)
			(end 0.7874 0.4064)
			(stroke
				(width 0.1524)
				(type default)
			)
			(layer "F.SilkS")
		)
		(fp_line
			(start -0.7874 0.4064)
			(end -0.7874 -0.4064)
			(stroke
				(width 0.1524)
				(type default)
			)
			(layer "F.SilkS")
		)
		(fp_line
			(start -0.7874 -0.4064)
			(end 0.7874 -0.4064)
			(stroke
				(width 0.1524)
				(type default)
			)
			(layer "F.SilkS")
		)
		(fp_line
			(start 0.67945 0.3048)
			(end 0.120396 0.3048)
			(stroke
				(width 0.1)
				(type default)
			)
			(layer "F.Fab")
		)
		(fp_line
			(start 0.67945 -0.3048)
			(end 0.67945 0.3048)
			(stroke
				(width 0.1)
				(type default)
			)
			(layer "F.Fab")
		)
		(fp_line
			(start 0.12065 -0.2794)
			(end 0.12065 -0.3048)
			(stroke
				(width 0.1)
				(type default)
			)
			(layer "F.Fab")
		)
		(fp_line
			(start 0.12065 -0.3048)
			(end 0.67945 -0.3048)
			(stroke
				(width 0.1)
				(type default)
			)
			(layer "F.Fab")
		)
		(fp_line
			(start 0.120396 0.3048)
			(end 0.120396 0.2794)
			(stroke
				(width 0.1)
				(type default)
			)
			(layer "F.Fab")
		)
		(fp_line
			(start 0.120396 0.2794)
			(end -0.12065 0.2794)
			(stroke
				(width 0.1)
				(type default)
			)
			(layer "F.Fab")
		)
		(fp_line
			(start -0.12065 0.3048)
			(end -0.67945 0.3048)
			(stroke
				(width 0.1)
				(type default)
			)
			(layer "F.Fab")
		)
		(fp_line
			(start -0.12065 0.2794)
			(end -0.12065 0.3048)
			(stroke
				(width 0.1)
				(type default)
			)
			(layer "F.Fab")
		)
		(fp_line
			(start -0.12065 -0.2794)
			(end 0.12065 -0.2794)
			(stroke
				(width 0.1)
				(type default)
			)
			(layer "F.Fab")
		)
		(fp_line
			(start -0.12065 -0.305054)
			(end -0.12065 -0.2794)
			(stroke
				(width 0.1)
				(type default)
			)
			(layer "F.Fab")
		)
		(fp_line
			(start -0.67945 0.3048)
			(end -0.67945 -0.305054)
			(stroke
				(width 0.1)
				(type default)
			)
			(layer "F.Fab")
		)
		(fp_line
			(start -0.67945 -0.305054)
			(end -0.12065 -0.305054)
			(stroke
				(width 0.1)
				(type default)
			)
			(layer "F.Fab")
		)
		(pad "1" smd circle
			(at -0.40005 0 180)
			(size 0 0)
			(layers "F.Cu" "F.Mask" "F.Paste")
			(net "SVID_DIO1_CPU0_R")
		)
		(pad "2" smd circle
			(at 0.40005 0 180)
			(size 0 0)
			(layers "F.Cu" "F.Mask" "F.Paste")
			(net "SVID_DIO_PVCCD_HV_CPU0_R")
		)
	)
	(footprint ""
		(layer "F.Cu")
		(at 77.77226 -128.8161)
		(property "Reference" "ME2"
			(at -9.652 -9.540748 0)
			(unlocked yes)
			(layer "F.SilkS")
			(effects
				(font
					(size 0.7874 0.5842)
					(thickness 0.1524)
				)
				(justify left)
			)
		)
		(property "Value" ""
			(at 0 0 0)
			(layer "F.Fab")
			(effects
				(font
					(size 1.27 1.27)
				)
			)
		)
		(duplicate_pad_numbers_are_jumpers no)
		(zone
			(layer "F.Cu")
			(hatch none 0.5)
			(connect_pads
				(clearance 0)
			)
			(min_thickness 0.25)
			(keepout
				(tracks allowed)
				(vias allowed)
				(pads allowed)
				(copperpour allowed)
				(footprints not_allowed)
			)
			(placement
				(enabled no)
				(sheetname "")
			)
			(fill
				(thermal_gap 0.5)
				(thermal_bridge_width 0.5)
				(island_removal_mode 0)
			)
			(polygon
				(pts
					(arc
						(start 87.77224 -128.8161)
						(mid 67.77228 -128.8161)
						(end 87.77224 -128.8161)
					)
				)
			)
		)
	)
)
